(kicad_pcb
	(version 20260206)
	(generator "pcbnew")
	(generator_version "10.0")
	(general
		(thickness 1.6)
		(legacy_teardrops no)
	)
	(paper "A4")
	(title_block
		(title "01162023_DA0F0TEBIF0_F0T_Expander_BD_F_brd_V02_OCP.brd")
		(comment 1 "Grand Teton / footprints 6932-6937 of 9728")
	)
	(layers
		(0 "F.Cu" signal "TOP")
		(4 "In1.Cu" signal "GND")
		(6 "In2.Cu" signal "VCC")
		(8 "In3.Cu" signal "VCC1")
		(10 "In4.Cu" signal "GND1")
		(12 "In5.Cu" signal "IN1")
		(14 "In6.Cu" signal "GND2")
		(16 "In7.Cu" signal "IN2")
		(18 "In8.Cu" signal "GND3")
		(20 "In9.Cu" signal "IN3")
		(22 "In10.Cu" signal "GND4")
		(24 "In11.Cu" signal "IN4")
		(26 "In12.Cu" signal "GND5")
		(28 "In13.Cu" signal "IN5")
		(30 "In14.Cu" signal "GND6")
		(32 "In15.Cu" signal "IN6")
		(34 "In16.Cu" signal "GND7")
		(2 "B.Cu" signal "BOTTOM")
		(9 "F.Adhes" user "F.Adhesive")
		(11 "B.Adhes" user "B.Adhesive")
		(13 "F.Paste" user "Package Geometry/Pastemask Top")
		(15 "B.Paste" user "Package Geometry/Pastemask Bottom")
		(5 "F.SilkS" user "Ref Des/Silkscreen Top")
		(7 "B.SilkS" user "Ref Des/Silkscreen Bottom")
		(1 "F.Mask" user "Board Geometry/Soldermask Top")
		(3 "B.Mask" user "Board Geometry/Soldermask Bottom")
		(17 "Dwgs.User" user "User.Drawings")
		(19 "Cmts.User" user "User.Comments")
		(21 "Eco1.User" user "User.Eco1")
		(23 "Eco2.User" user "User.Eco2")
		(25 "Edge.Cuts" user "Board Geometry/Outline")
		(27 "Margin" user)
		(31 "F.CrtYd" user "Package Geometry/Place Bound Top")
		(29 "B.CrtYd" user "Package Geometry/Place Bound Bottom")
		(35 "F.Fab" user "Ref Des/Assembly Top")
		(33 "B.Fab" user "Ref Des/Assembly Bottom")
	)
	(footprint ""
		(layer "F.Cu")
		(at 367.77168 -25.342342 -90)
		(property "Reference" "R445"
			(at 0 0 270)
			(layer "F.SilkS")
			(hide yes)
			(effects
				(font
					(size 1.27 1.27)
				)
			)
		)
		(property "Value" ""
			(at 0 0 270)
			(layer "F.Fab")
			(effects
				(font
					(size 1.27 1.27)
				)
			)
		)
		(duplicate_pad_numbers_are_jumpers no)
		(fp_line
			(start -0.7874 0.4064)
			(end -0.7874 -0.4064)
			(stroke
				(width 0.1524)
				(type default)
			)
			(layer "F.SilkS")
		)
		(fp_line
			(start 0.7874 0.4064)
			(end -0.7874 0.4064)
			(stroke
				(width 0.1524)
				(type default)
			)
			(layer "F.SilkS")
		)
		(fp_line
			(start -0.7874 -0.4064)
			(end 0.7874 -0.4064)
			(stroke
				(width 0.1524)
				(type default)
			)
			(layer "F.SilkS")
		)
		(fp_line
			(start 0.7874 -0.4064)
			(end 0.7874 0.4064)
			(stroke
				(width 0.1524)
				(type default)
			)
			(layer "F.SilkS")
		)
		(fp_line
			(start -0.67945 0.3048)
			(end -0.67945 -0.305054)
			(stroke
				(width 0.1)
				(type default)
			)
			(layer "F.Fab")
		)
		(fp_line
			(start -0.12065 0.3048)
			(end -0.67945 0.3048)
			(stroke
				(width 0.1)
				(type default)
			)
			(layer "F.Fab")
		)
		(fp_line
			(start 0.120396 0.3048)
			(end 0.120396 0.2794)
			(stroke
				(width 0.1)
				(type default)
			)
			(layer "F.Fab")
		)
		(fp_line
			(start 0.67945 0.3048)
			(end 0.120396 0.3048)
			(stroke
				(width 0.1)
				(type default)
			)
			(layer "F.Fab")
		)
		(fp_line
			(start -0.12065 0.2794)
			(end -0.12065 0.3048)
			(stroke
				(width 0.1)
				(type default)
			)
			(layer "F.Fab")
		)
		(fp_line
			(start 0.120396 0.2794)
			(end -0.12065 0.2794)
			(stroke
				(width 0.1)
				(type default)
			)
			(layer "F.Fab")
		)
		(fp_line
			(start -0.12065 -0.2794)
			(end 0.12065 -0.2794)
			(stroke
				(width 0.1)
				(type default)
			)
			(layer "F.Fab")
		)
		(fp_line
			(start 0.12065 -0.2794)
			(end 0.12065 -0.3048)
			(stroke
				(width 0.1)
				(type default)
			)
			(layer "F.Fab")
		)
		(fp_line
			(start 0.12065 -0.3048)
			(end 0.67945 -0.3048)
			(stroke
				(width 0.1)
				(type default)
			)
			(layer "F.Fab")
		)
		(fp_line
			(start 0.67945 -0.3048)
			(end 0.67945 0.3048)
			(stroke
				(width 0.1)
				(type default)
			)
			(layer "F.Fab")
		)
		(fp_line
			(start -0.67945 -0.305054)
			(end -0.12065 -0.305054)
			(stroke
				(width 0.1)
				(type default)
			)
			(layer "F.Fab")
		)
		(fp_line
			(start -0.12065 -0.305054)
			(end -0.12065 -0.2794)
			(stroke
				(width 0.1)
				(type default)
			)
			(layer "F.Fab")
		)
		(pad "1" smd circle
			(at -0.40005 0 270)
			(size 0 0)
			(layers "F.Cu" "F.Mask" "F.Paste")
			(net "P3V3_SSD12")
		)
		(pad "2" smd circle
			(at 0.40005 0 270)
			(size 0 0)
			(layers "F.Cu" "F.Mask" "F.Paste")
			(net "DUALPORT_N_SSD12")
		)
	)
	(footprint ""
		(layer "F.Cu")
		(at 178.731926 -169.040302 -90)
		(property "Reference" "U22"
			(at -0.17907 -3.529584 0)
			(unlocked yes)
			(layer "F.SilkS")
			(effects
				(font
					(size 0.7874 0.5842)
					(thickness 0.1524)
				)
			)
		)
		(property "Value" ""
			(at 0 0 270)
			(layer "F.Fab")
			(effects
				(font
					(size 1.27 1.27)
				)
			)
		)
		(duplicate_pad_numbers_are_jumpers no)
		(fp_line
			(start -1.905 1.651)
			(end -1.905 -1.651)
			(stroke
				(width 0.1524)
				(type default)
			)
			(layer "F.SilkS")
		)
		(fp_line
			(start 1.905 1.651)
			(end -1.905 1.651)
			(stroke
				(width 0.1524)
				(type default)
			)
			(layer "F.SilkS")
		)
		(fp_line
			(start -1.905 -1.651)
			(end 1.905 -1.651)
			(stroke
				(width 0.1524)
				(type default)
			)
			(layer "F.SilkS")
		)
		(fp_line
			(start 1.905 -1.651)
			(end 1.905 1.651)
			(stroke
				(width 0.1524)
				(type default)
			)
			(layer "F.SilkS")
		)
		(fp_line
			(start -0.649986 1.524)
			(end -0.649986 1.169924)
			(stroke
				(width 0.1)
				(type default)
			)
			(layer "F.Fab")
		)
		(fp_line
			(start 0.6985 1.524)
			(end -0.649986 1.524)
			(stroke
				(width 0.1)
				(type default)
			)
			(layer "F.Fab")
		)
		(fp_line
			(start -1.249934 1.169924)
			(end -1.249934 0.729996)
			(stroke
				(width 0.1)
				(type default)
			)
			(layer "F.Fab")
		)
		(fp_line
			(start -0.649986 1.169924)
			(end -1.249934 1.169924)
			(stroke
				(width 0.1)
				(type default)
			)
			(layer "F.Fab")
		)
		(fp_line
			(start -1.249934 0.729996)
			(end -0.6985 0.729996)
			(stroke
				(width 0.1)
				(type default)
			)
			(layer "F.Fab")
		)
		(fp_line
			(start -0.6985 0.729996)
			(end -0.6985 -0.729996)
			(stroke
				(width 0.1)
				(type default)
			)
			(layer "F.Fab")
		)
		(fp_line
			(start 0.6985 0.219964)
			(end 0.6985 1.524)
			(stroke
				(width 0.1)
				(type default)
			)
			(layer "F.Fab")
		)
		(fp_line
			(start 1.249934 0.219964)
			(end 0.6985 0.219964)
			(stroke
				(width 0.1)
				(type default)
			)
			(layer "F.Fab")
		)
		(fp_line
			(start 0.6985 -0.219964)
			(end 1.249934 -0.219964)
			(stroke
				(width 0.1)
				(type default)
			)
			(layer "F.Fab")
		)
		(fp_line
			(start 1.249934 -0.219964)
			(end 1.249934 0.219964)
			(stroke
				(width 0.1)
				(type default)
			)
			(layer "F.Fab")
		)
		(fp_line
			(start -1.249934 -0.729996)
			(end -1.249934 -1.169924)
			(stroke
				(width 0.1)
				(type default)
			)
			(layer "F.Fab")
		)
		(fp_line
			(start -0.6985 -0.729996)
			(end -1.249934 -0.729996)
			(stroke
				(width 0.1)
				(type default)
			)
			(layer "F.Fab")
		)
		(fp_line
			(start -1.249934 -1.169924)
			(end -0.649986 -1.169924)
			(stroke
				(width 0.1)
				(type default)
			)
			(layer "F.Fab")
		)
		(fp_line
			(start -0.649986 -1.169924)
			(end -0.649986 -1.524)
			(stroke
				(width 0.1)
				(type default)
			)
			(layer "F.Fab")
		)
		(fp_line
			(start -0.649986 -1.524)
			(end 0.6985 -1.524)
			(stroke
				(width 0.1)
				(type default)
			)
			(layer "F.Fab")
		)
		(fp_line
			(start 0.6985 -1.524)
			(end 0.6985 -0.219964)
			(stroke
				(width 0.1)
				(type default)
			)
			(layer "F.Fab")
		)
		(pad "1" smd rect
			(at -1.1176 -1.016 180)
			(size 1.016 1.27)
			(layers "F.Cu" "F.Mask" "F.Paste")
			(net "HP_NIC2_PWRGD")
		)
		(pad "2" smd rect
			(at -1.1176 1.016 180)
			(size 1.016 1.27)
			(layers "F.Cu" "F.Mask" "F.Paste")
			(net "P3V3_NIC2")
		)
		(pad "3" smd rect
			(at 1.1176 0 180)
			(size 1.016 1.27)
			(layers "F.Cu" "F.Mask" "F.Paste")
			(net "GND")
		)
	)
	(footprint ""
		(layer "F.Cu")
		(at 381.254 -210.566)
		(property "Reference" "R4608"
			(at 0 0 0)
			(layer "F.SilkS")
			(hide yes)
			(effects
				(font
					(size 1.27 1.27)
				)
			)
		)
		(property "Value" ""
			(at 0 0 0)
			(layer "F.Fab")
			(effects
				(font
					(size 1.27 1.27)
				)
			)
		)
		(duplicate_pad_numbers_are_jumpers no)
		(fp_line
			(start -0.7874 -0.4064)
			(end 0.7874 -0.4064)
			(stroke
				(width 0.1524)
				(type default)
			)
			(layer "F.SilkS")
		)
		(fp_line
			(start -0.7874 0.4064)
			(end -0.7874 -0.4064)
			(stroke
				(width 0.1524)
				(type default)
			)
			(layer "F.SilkS")
		)
		(fp_line
			(start 0.7874 -0.4064)
			(end 0.7874 0.4064)
			(stroke
				(width 0.1524)
				(type default)
			)
			(layer "F.SilkS")
		)
		(fp_line
			(start 0.7874 0.4064)
			(end -0.7874 0.4064)
			(stroke
				(width 0.1524)
				(type default)
			)
			(layer "F.SilkS")
		)
		(fp_line
			(start -0.67945 -0.305054)
			(end -0.12065 -0.305054)
			(stroke
				(width 0.1)
				(type default)
			)
			(layer "F.Fab")
		)
		(fp_line
			(start -0.67945 0.3048)
			(end -0.67945 -0.305054)
			(stroke
				(width 0.1)
				(type default)
			)
			(layer "F.Fab")
		)
		(fp_line
			(start -0.12065 -0.305054)
			(end -0.12065 -0.2794)
			(stroke
				(width 0.1)
				(type default)
			)
			(layer "F.Fab")
		)
		(fp_line
			(start -0.12065 -0.2794)
			(end 0.12065 -0.2794)
			(stroke
				(width 0.1)
				(type default)
			)
			(layer "F.Fab")
		)
		(fp_line
			(start -0.12065 0.2794)
			(end -0.12065 0.3048)
			(stroke
				(width 0.1)
				(type default)
			)
			(layer "F.Fab")
		)
		(fp_line
			(start -0.12065 0.3048)
			(end -0.67945 0.3048)
			(stroke
				(width 0.1)
				(type default)
			)
			(layer "F.Fab")
		)
		(fp_line
			(start 0.120396 0.2794)
			(end -0.12065 0.2794)
			(stroke
				(width 0.1)
				(type default)
			)
			(layer "F.Fab")
		)
		(fp_line
			(start 0.120396 0.3048)
			(end 0.120396 0.2794)
			(stroke
				(width 0.1)
				(type default)
			)
			(layer "F.Fab")
		)
		(fp_line
			(start 0.12065 -0.3048)
			(end 0.67945 -0.3048)
			(stroke
				(width 0.1)
				(type default)
			)
			(layer "F.Fab")
		)
		(fp_line
			(start 0.12065 -0.2794)
			(end 0.12065 -0.3048)
			(stroke
				(width 0.1)
				(type default)
			)
			(layer "F.Fab")
		)
		(fp_line
			(start 0.67945 -0.3048)
			(end 0.67945 0.3048)
			(stroke
				(width 0.1)
				(type default)
			)
			(layer "F.Fab")
		)
		(fp_line
			(start 0.67945 0.3048)
			(end 0.120396 0.3048)
			(stroke
				(width 0.1)
				(type default)
			)
			(layer "F.Fab")
		)
		(pad "1" smd circle
			(at -0.40005 0)
			(size 0 0)
			(layers "F.Cu" "F.Mask" "F.Paste")
			(net "P3V3_AUX")
		)
		(pad "2" smd circle
			(at 0.40005 0)
			(size 0 0)
			(layers "F.Cu" "F.Mask" "F.Paste")
			(net "RST_PEX_NIC0_PERST_R_N")
		)
	)
	(footprint ""
		(layer "F.Cu")
		(at 262.564626 -240.851944 90)
		(property "Reference" "R6580"
			(at 0 0 90)
			(layer "F.SilkS")
			(hide yes)
			(effects
				(font
					(size 1.27 1.27)
				)
			)
		)
		(property "Value" ""
			(at 0 0 90)
			(layer "F.Fab")
			(effects
				(font
					(size 1.27 1.27)
				)
			)
		)
		(duplicate_pad_numbers_are_jumpers no)
		(fp_line
			(start 0.7874 -0.4064)
			(end 0.7874 0.4064)
			(stroke
				(width 0.1524)
				(type default)
			)
			(layer "F.SilkS")
		)
		(fp_line
			(start -0.7874 -0.4064)
			(end 0.7874 -0.4064)
			(stroke
				(width 0.1524)
				(type default)
			)
			(layer "F.SilkS")
		)
		(fp_line
			(start 0.7874 0.4064)
			(end -0.7874 0.4064)
			(stroke
				(width 0.1524)
				(type default)
			)
			(layer "F.SilkS")
		)
		(fp_line
			(start -0.7874 0.4064)
			(end -0.7874 -0.4064)
			(stroke
				(width 0.1524)
				(type default)
			)
			(layer "F.SilkS")
		)
		(fp_line
			(start -0.12065 -0.305054)
			(end -0.12065 -0.2794)
			(stroke
				(width 0.1)
				(type default)
			)
			(layer "F.Fab")
		)
		(fp_line
			(start -0.67945 -0.305054)
			(end -0.12065 -0.305054)
			(stroke
				(width 0.1)
				(type default)
			)
			(layer "F.Fab")
		)
		(fp_line
			(start 0.67945 -0.3048)
			(end 0.67945 0.3048)
			(stroke
				(width 0.1)
				(type default)
			)
			(layer "F.Fab")
		)
		(fp_line
			(start 0.12065 -0.3048)
			(end 0.67945 -0.3048)
			(stroke
				(width 0.1)
				(type default)
			)
			(layer "F.Fab")
		)
		(fp_line
			(start 0.12065 -0.2794)
			(end 0.12065 -0.3048)
			(stroke
				(width 0.1)
				(type default)
			)
			(layer "F.Fab")
		)
		(fp_line
			(start -0.12065 -0.2794)
			(end 0.12065 -0.2794)
			(stroke
				(width 0.1)
				(type default)
			)
			(layer "F.Fab")
		)
		(fp_line
			(start 0.120396 0.2794)
			(end -0.12065 0.2794)
			(stroke
				(width 0.1)
				(type default)
			)
			(layer "F.Fab")
		)
		(fp_line
			(start -0.12065 0.2794)
			(end -0.12065 0.3048)
			(stroke
				(width 0.1)
				(type default)
			)
			(layer "F.Fab")
		)
		(fp_line
			(start 0.67945 0.3048)
			(end 0.120396 0.3048)
			(stroke
				(width 0.1)
				(type default)
			)
			(layer "F.Fab")
		)
		(fp_line
			(start 0.120396 0.3048)
			(end 0.120396 0.2794)
			(stroke
				(width 0.1)
				(type default)
			)
			(layer "F.Fab")
		)
		(fp_line
			(start -0.12065 0.3048)
			(end -0.67945 0.3048)
			(stroke
				(width 0.1)
				(type default)
			)
			(layer "F.Fab")
		)
		(fp_line
			(start -0.67945 0.3048)
			(end -0.67945 -0.305054)
			(stroke
				(width 0.1)
				(type default)
			)
			(layer "F.Fab")
		)
		(pad "1" smd circle
			(at -0.40005 0 90)
			(size 0 0)
			(layers "F.Cu" "F.Mask" "F.Paste")
			(net "P1V8_PLL_PEX2_ADJ")
		)
		(pad "2" smd circle
			(at 0.40005 0 90)
			(size 0 0)
			(layers "F.Cu" "F.Mask" "F.Paste")
			(net "GND")
		)
	)
	(footprint ""
		(layer "F.Cu")
		(at 327.533 -208.153 180)
		(property "Reference" "R5911"
			(at 0 0 180)
			(layer "F.SilkS")
			(hide yes)
			(effects
				(font
					(size 1.27 1.27)
				)
			)
		)
		(property "Value" ""
			(at 0 0 180)
			(layer "F.Fab")
			(effects
				(font
					(size 1.27 1.27)
				)
			)
		)
		(duplicate_pad_numbers_are_jumpers no)
		(fp_line
			(start 0.7874 0.4064)
			(end -0.7874 0.4064)
			(stroke
				(width 0.1524)
				(type default)
			)
			(layer "F.SilkS")
		)
		(fp_line
			(start 0.7874 -0.4064)
			(end 0.7874 0.4064)
			(stroke
				(width 0.1524)
				(type default)
			)
			(layer "F.SilkS")
		)
		(fp_line
			(start -0.7874 0.4064)
			(end -0.7874 -0.4064)
			(stroke
				(width 0.1524)
				(type default)
			)
			(layer "F.SilkS")
		)
		(fp_line
			(start -0.7874 -0.4064)
			(end 0.7874 -0.4064)
			(stroke
				(width 0.1524)
				(type default)
			)
			(layer "F.SilkS")
		)
		(fp_line
			(start 0.67945 0.3048)
			(end 0.120396 0.3048)
			(stroke
				(width 0.1)
				(type default)
			)
			(layer "F.Fab")
		)
		(fp_line
			(start 0.67945 -0.3048)
			(end 0.67945 0.3048)
			(stroke
				(width 0.1)
				(type default)
			)
			(layer "F.Fab")
		)
		(fp_line
			(start 0.12065 -0.2794)
			(end 0.12065 -0.3048)
			(stroke
				(width 0.1)
				(type default)
			)
			(layer "F.Fab")
		)
		(fp_line
			(start 0.12065 -0.3048)
			(end 0.67945 -0.3048)
			(stroke
				(width 0.1)
				(type default)
			)
			(layer "F.Fab")
		)
		(fp_line
			(start 0.120396 0.3048)
			(end 0.120396 0.2794)
			(stroke
				(width 0.1)
				(type default)
			)
			(layer "F.Fab")
		)
		(fp_line
			(start 0.120396 0.2794)
			(end -0.12065 0.2794)
			(stroke
				(width 0.1)
				(type default)
			)
			(layer "F.Fab")
		)
		(fp_line
			(start -0.12065 0.3048)
			(end -0.67945 0.3048)
			(stroke
				(width 0.1)
				(type default)
			)
			(layer "F.Fab")
		)
		(fp_line
			(start -0.12065 0.2794)
			(end -0.12065 0.3048)
			(stroke
				(width 0.1)
				(type default)
			)
			(layer "F.Fab")
		)
		(fp_line
			(start -0.12065 -0.2794)
			(end 0.12065 -0.2794)
			(stroke
				(width 0.1)
				(type default)
			)
			(layer "F.Fab")
		)
		(fp_line
			(start -0.12065 -0.305054)
			(end -0.12065 -0.2794)
			(stroke
				(width 0.1)
				(type default)
			)
			(layer "F.Fab")
		)
		(fp_line
			(start -0.67945 0.3048)
			(end -0.67945 -0.305054)
			(stroke
				(width 0.1)
				(type default)
			)
			(layer "F.Fab")
		)
		(fp_line
			(start -0.67945 -0.305054)
			(end -0.12065 -0.305054)
			(stroke
				(width 0.1)
				(type default)
			)
			(layer "F.Fab")
		)
		(pad "1" smd circle
			(at -0.40005 0 180)
			(size 0 0)
			(layers "F.Cu" "F.Mask" "F.Paste")
			(net "HSC_TIMER_R_N")
		)
		(pad "2" smd circle
			(at 0.40005 0 180)
			(size 0 0)
			(layers "F.Cu" "F.Mask" "F.Paste")
			(net "P3V3_AUX")
		)
	)
	(footprint ""
		(layer "F.Cu")
		(at 126.221236 -176.023524)
		(property "Reference" "R1088"
			(at 0 0 0)
			(layer "F.SilkS")
			(hide yes)
			(effects
				(font
					(size 1.27 1.27)
				)
			)
		)
		(property "Value" ""
			(at 0 0 0)
			(layer "F.Fab")
			(effects
				(font
					(size 1.27 1.27)
				)
			)
		)
		(duplicate_pad_numbers_are_jumpers no)
		(fp_line
			(start 0.7874 0.4064)
			(end -0.7874 0.4064)
			(stroke
				(width 0.1524)
				(type default)
			)
			(layer "F.SilkS")
		)
		(fp_line
			(start -0.67945 -0.305054)
			(end -0.12065 -0.305054)
			(stroke
				(width 0.1)
				(type default)
			)
			(layer "F.Fab")
		)
		(fp_line
			(start -0.67945 0.3048)
			(end -0.67945 -0.305054)
			(stroke
				(width 0.1)
				(type default)
			)
			(layer "F.Fab")
		)
		(fp_line
			(start -0.12065 -0.305054)
			(end -0.12065 -0.2794)
			(stroke
				(width 0.1)
				(type default)
			)
			(layer "F.Fab")
		)
		(fp_line
			(start -0.12065 -0.2794)
			(end 0.12065 -0.2794)
			(stroke
				(width 0.1)
				(type default)
			)
			(layer "F.Fab")
		)
		(fp_line
			(start -0.12065 0.2794)
			(end -0.12065 0.3048)
			(stroke
				(width 0.1)
				(type default)
			)
			(layer "F.Fab")
		)
		(fp_line
			(start -0.12065 0.3048)
			(end -0.67945 0.3048)
			(stroke
				(width 0.1)
				(type default)
			)
			(layer "F.Fab")
		)
		(fp_line
			(start 0.120396 0.2794)
			(end -0.12065 0.2794)
			(stroke
				(width 0.1)
				(type default)
			)
			(layer "F.Fab")
		)
		(fp_line
			(start 0.120396 0.3048)
			(end 0.120396 0.2794)
			(stroke
				(width 0.1)
				(type default)
			)
			(layer "F.Fab")
		)
		(fp_line
			(start 0.12065 -0.3048)
			(end 0.67945 -0.3048)
			(stroke
				(width 0.1)
				(type default)
			)
			(layer "F.Fab")
		)
		(fp_line
			(start 0.12065 -0.2794)
			(end 0.12065 -0.3048)
			(stroke
				(width 0.1)
				(type default)
			)
			(layer "F.Fab")
		)
		(fp_line
			(start 0.67945 -0.3048)
			(end 0.67945 0.3048)
			(stroke
				(width 0.1)
				(type default)
			)
			(layer "F.Fab")
		)
		(fp_line
			(start 0.67945 0.3048)
			(end 0.120396 0.3048)
			(stroke
				(width 0.1)
				(type default)
			)
			(layer "F.Fab")
		)
		(pad "1" smd circle
			(at -0.40005 0)
			(size 0 0)
			(layers "F.Cu" "F.Mask" "F.Paste")
			(net "CLK_100M_DB2000QL_PEX0_S1_R_DN")
		)
		(pad "2" smd circle
			(at 0.40005 0)
			(size 0 0)
			(layers "F.Cu" "F.Mask" "F.Paste")
			(net "CLK_100M_DB2000QL_PEX0_S1_DN")
		)
	)
)
